(kicad_pcb
	(version 20260206)
	(generator "pcbnew")
	(generator_version "10.0")
	(general
		(thickness 1.6)
		(legacy_teardrops no)
	)
	(paper "A4")
	(title_block
		(title "Wiwynn_Tioga_Pass_MB.brd")
		(comment 1 "Tioga Pass / footprint 1664 of 4770 (U7C1), pads 922-1035 of 1310")
	)
	(layers
		(0 "F.Cu" signal "TOP")
		(4 "In1.Cu" signal "L2GND")
		(6 "In2.Cu" signal "L3")
		(8 "In3.Cu" signal "L4GND")
		(10 "In4.Cu" signal "L5")
		(12 "In5.Cu" signal "L6GND")
		(14 "In6.Cu" signal "L7VCC")
		(16 "In7.Cu" signal "L8VCC")
		(18 "In8.Cu" signal "L9GND")
		(20 "In9.Cu" signal "L10")
		(22 "In10.Cu" signal "L11GND")
		(24 "In11.Cu" signal "L12")
		(26 "In12.Cu" signal "L13GND")
		(2 "B.Cu" signal "BOTTOM")
		(9 "F.Adhes" user "F.Adhesive")
		(11 "B.Adhes" user "B.Adhesive")
		(13 "F.Paste" user "Package Geometry/Pastemask Top")
		(15 "B.Paste" user "Package Geometry/Pastemask Bottom")
		(5 "F.SilkS" user "Ref Des/Silkscreen Top")
		(7 "B.SilkS" user "Ref Des/Silkscreen Bottom")
		(1 "F.Mask" user "Board Geometry/Soldermask Top")
		(3 "B.Mask" user "Board Geometry/Soldermask Bottom")
		(17 "Dwgs.User" user "User.Drawings")
		(19 "Cmts.User" user "User.Comments")
		(21 "Eco1.User" user "User.Eco1")
		(23 "Eco2.User" user "User.Eco2")
		(25 "Edge.Cuts" user "Board Geometry/Outline")
		(27 "Margin" user)
		(31 "F.CrtYd" user "Package Geometry/Place Bound Top")
		(29 "B.CrtYd" user "Package Geometry/Place Bound Bottom")
		(35 "F.Fab" user "Ref Des/Assembly Top")
		(33 "B.Fab" user "Ref Des/Assembly Bottom")
	)
	(footprint ""
		(layer "F.Cu")
		(at 387.985 -109.855 90)
		(property "Reference" "U7C1"
			(at 17.75333 -13.335 0)
			(unlocked yes)
			(layer "F.SilkS")
			(effects
				(font
					(size 0.7874 0.5842)
					(thickness 0.1524)
				)
				(justify left)
			)
		)
		(property "Value" ""
			(at 0 0 90)
			(layer "F.Fab")
			(effects
				(font
					(size 1.27 1.27)
				)
			)
		)
		(duplicate_pad_numbers_are_jumpers no)
		(pad "C52" smd circle
			(at 6.999986 -12.480036 90)
			(size 0.3048 0.3048)
			(layers "F.Cu" "F.Mask" "F.Paste")
			(net "P3E_CPU0_PE1_PCH_TXN<4>")
		)
		(pad "C54" smd circle
			(at 7.999984 -12.480036 90)
			(size 0.3048 0.3048)
			(layers "F.Cu" "F.Mask" "F.Paste")
			(net "P3E_CPU0_PE1_PCH_TXN<6>")
		)
		(pad "C57" smd circle
			(at 8.999982 -12.480036 90)
			(size 0.3048 0.3048)
			(layers "F.Cu" "F.Mask" "F.Paste")
			(net "P3E_CPU0_PE1_PCH_C_TXP<8>")
		)
		(pad "C59" smd circle
			(at 9.99998 -12.480036 90)
			(size 0.3048 0.3048)
			(layers "F.Cu" "F.Mask" "F.Paste")
			(net "P3E_CPU0_PE1_PCH_C_TXP<10>")
		)
		(pad "C61" smd circle
			(at 10.999978 -12.480036 90)
			(size 0.3048 0.3048)
			(layers "F.Cu" "F.Mask" "F.Paste")
			(net "P3E_CPU0_PE1_PCH_C_TXP<12>")
		)
		(pad "C63" smd circle
			(at 11.999976 -12.480036 90)
			(size 0.3048 0.3048)
			(layers "F.Cu" "F.Mask" "F.Paste")
			(net "P3E_CPU0_PE1_PCH_C_TXP<14>")
		)
		(pad "C65" smd circle
			(at 12.999974 -12.480036 90)
			(size 0.3048 0.3048)
			(layers "F.Cu" "F.Mask" "F.Paste")
			(net "GND")
		)
		(pad "C67" smd circle
			(at 13.999972 -12.580112 90)
			(size 0.3556 0.3556)
			(layers "F.Cu" "F.Mask" "F.Paste")
			(net "TP_PCH_RSVD13")
		)
		(pad "C68" smd circle
			(at 14.784324 -12.580112 90)
			(size 0.3556 0.3556)
			(layers "F.Cu" "F.Mask" "F.Paste")
			(net "TP_PCH_RSVD12")
		)
		(pad "C70" smd circle
			(at 15.497302 -12.497308 45)
			(size 0.4064 0.4064)
			(layers "F.Cu" "F.Mask" "F.Paste")
			(net "FM_PCH_PRSNT_N")
		)
		(pad "C72" smd circle
			(at 16.310102 -12.502134 45)
			(size 0.5588 0.5588)
			(layers "F.Cu" "F.Mask" "F.Paste")
			(net "GND")
		)
		(pad "CA3" smd circle
			(at -15.502128 13.310108 225)
			(size 0.5588 0.5588)
			(layers "F.Cu" "F.Mask" "F.Paste")
			(net "GND")
		)
		(pad "CA5" smd circle
			(at -14.689328 13.310108 225)
			(size 0.4064 0.4064)
			(layers "F.Cu" "F.Mask" "F.Paste")
			(net "GND")
		)
		(pad "CA7" smd circle
			(at -13.876528 13.310108 225)
			(size 0.4064 0.4064)
			(layers "F.Cu" "F.Mask" "F.Paste")
			(net "GND")
		)
		(pad "CA9" smd circle
			(at -13.063728 13.310108 90)
			(size 0.3556 0.3556)
			(layers "F.Cu" "F.Mask" "F.Paste")
			(net "GND")
		)
		(pad "CA11" smd oval
			(at -11.999976 13.310108 90)
			(size 0.254 0.3302)
			(layers "F.Cu" "F.Mask" "F.Paste")
			(net "TP_PCH_GPP_J17")
		)
		(pad "CA13" smd oval
			(at -10.999978 13.310108 90)
			(size 0.254 0.3302)
			(layers "F.Cu" "F.Mask" "F.Paste")
			(net "LED_GBE_P3_0")
		)
		(pad "CA15" smd oval
			(at -9.99998 13.310108 90)
			(size 0.254 0.3302)
			(layers "F.Cu" "F.Mask" "F.Paste")
			(net "GND")
		)
		(pad "CA18" smd oval
			(at -8.999982 13.310108 90)
			(size 0.254 0.3302)
			(layers "F.Cu" "F.Mask" "F.Paste")
			(net "GND")
		)
		(pad "CA20" smd oval
			(at -7.999984 13.310108 90)
			(size 0.254 0.3302)
			(layers "F.Cu" "F.Mask" "F.Paste")
			(net "JTAG_PCH_GBE_TDO")
		)
		(pad "CA22" smd oval
			(at -6.999986 13.310108 90)
			(size 0.254 0.3302)
			(layers "F.Cu" "F.Mask" "F.Paste")
			(net "JTAG_PCH_GBE_TMS")
		)
		(pad "CA24" smd oval
			(at -5.999988 13.310108 90)
			(size 0.254 0.3302)
			(layers "F.Cu" "F.Mask" "F.Paste")
			(net "JTAG_PCH_GBE_TRST_N")
		)
		(pad "CA26" smd oval
			(at -4.99999 13.310108 90)
			(size 0.254 0.3302)
			(layers "F.Cu" "F.Mask" "F.Paste")
			(net "GND")
		)
		(pad "CA28" smd oval
			(at -3.999992 13.310108 90)
			(size 0.254 0.3302)
			(layers "F.Cu" "F.Mask" "F.Paste")
			(net "SMB_PMBUS_BMC_STBY_LVC3_SCL_R1")
		)
		(pad "CA30" smd oval
			(at -2.999994 13.310108 90)
			(size 0.254 0.3302)
			(layers "F.Cu" "F.Mask" "F.Paste")
			(net "FM_BOARD_REV_ID0")
		)
		(pad "CA32" smd oval
			(at -1.999996 13.310108 90)
			(size 0.254 0.3302)
			(layers "F.Cu" "F.Mask" "F.Paste")
			(net "FM_SLT_CFG0")
		)
		(pad "CA34" smd oval
			(at -0.999998 13.310108 90)
			(size 0.254 0.3302)
			(layers "F.Cu" "F.Mask" "F.Paste")
			(net "IRQ_BMC_PCH_SMI_LPC_N")
		)
		(pad "CA37" smd oval
			(at 0 13.310108 90)
			(size 0.254 0.3302)
			(layers "F.Cu" "F.Mask" "F.Paste")
			(net "FM_CPU_CATERR_DLY_LVT3_R_N")
		)
		(pad "CA39" smd oval
			(at 0.999998 13.310108 90)
			(size 0.254 0.3302)
			(layers "F.Cu" "F.Mask" "F.Paste")
			(net "FM_THROTTLE_R2_N")
		)
		(pad "CA41" smd oval
			(at 1.999996 13.310108 90)
			(size 0.254 0.3302)
			(layers "F.Cu" "F.Mask" "F.Paste")
			(net "FM_XRC_READY_N")
		)
		(pad "CA43" smd oval
			(at 2.999994 13.310108 90)
			(size 0.254 0.3302)
			(layers "F.Cu" "F.Mask" "F.Paste")
			(net "FM_ADR_MODE_SEL_R")
		)
		(pad "CA45" smd oval
			(at 3.999992 13.310108 90)
			(size 0.254 0.3302)
			(layers "F.Cu" "F.Mask" "F.Paste")
			(net "FM_BMC_CPLD_GPO")
		)
		(pad "CA48" smd oval
			(at 4.99999 13.310108 90)
			(size 0.254 0.3302)
			(layers "F.Cu" "F.Mask" "F.Paste")
			(net "FM_BMC_HEARTBEAT_N")
		)
		(pad "CA50" smd oval
			(at 5.999988 13.310108 90)
			(size 0.254 0.3302)
			(layers "F.Cu" "F.Mask" "F.Paste")
			(net "GND")
		)
		(pad "CA52" smd oval
			(at 6.999986 13.310108 90)
			(size 0.254 0.3302)
			(layers "F.Cu" "F.Mask" "F.Paste")
			(net "GND")
		)
		(pad "CA54" smd oval
			(at 7.999984 13.310108 90)
			(size 0.254 0.3302)
			(layers "F.Cu" "F.Mask" "F.Paste")
			(net "TP_USB2_P11_DN")
		)
		(pad "CA57" smd oval
			(at 8.999982 13.310108 90)
			(size 0.254 0.3302)
			(layers "F.Cu" "F.Mask" "F.Paste")
			(net "TP_USB2_P07_DN")
		)
		(pad "CA59" smd oval
			(at 9.99998 13.310108 90)
			(size 0.254 0.3302)
			(layers "F.Cu" "F.Mask" "F.Paste")
			(net "TP_USB2_P03_DN")
		)
		(pad "CA61" smd oval
			(at 10.999978 13.310108 90)
			(size 0.254 0.3302)
			(layers "F.Cu" "F.Mask" "F.Paste")
			(net "USB2_P02_DN_R")
		)
		(pad "CA63" smd oval
			(at 11.999976 13.310108 90)
			(size 0.254 0.3302)
			(layers "F.Cu" "F.Mask" "F.Paste")
			(net "TP_USB2_P06_DN")
		)
		(pad "CA65" smd circle
			(at 13.063728 13.310108 90)
			(size 0.3556 0.3556)
			(layers "F.Cu" "F.Mask" "F.Paste")
			(net "GND")
		)
		(pad "CA66" smd circle
			(at 13.876528 13.310108 315)
			(size 0.4064 0.4064)
			(layers "F.Cu" "F.Mask" "F.Paste")
			(net "GND")
		)
		(pad "CA68" smd circle
			(at 14.689328 13.310108 315)
			(size 0.4064 0.4064)
			(layers "F.Cu" "F.Mask" "F.Paste")
			(net "GND")
		)
		(pad "CA70" smd circle
			(at 15.502128 13.310108 315)
			(size 0.5588 0.5588)
			(layers "F.Cu" "F.Mask" "F.Paste")
			(net "GND")
		)
		(pad "D8" smd circle
			(at -13.5001 -12.065 90)
			(size 0.3048 0.3048)
			(layers "F.Cu" "F.Mask" "F.Paste")
			(net "FM_WBG_PRSNT_N")
		)
		(pad "D10" smd circle
			(at -12.500102 -12.065 90)
			(size 0.3048 0.3048)
			(layers "F.Cu" "F.Mask" "F.Paste")
			(net "TP_PCH_RSVD20")
		)
		(pad "D12" smd circle
			(at -11.500104 -12.065 90)
			(size 0.3048 0.3048)
			(layers "F.Cu" "F.Mask" "F.Paste")
			(net "GND")
		)
		(pad "D14" smd circle
			(at -10.500106 -12.065 90)
			(size 0.3048 0.3048)
			(layers "F.Cu" "F.Mask" "F.Paste")
			(net "FM_SLPS3_R_N")
		)
		(pad "D16" smd circle
			(at -9.500108 -12.065 90)
			(size 0.3048 0.3048)
			(layers "F.Cu" "F.Mask" "F.Paste")
			(net "GND")
		)
		(pad "D19" smd circle
			(at -8.50011 -12.065 90)
			(size 0.3048 0.3048)
			(layers "F.Cu" "F.Mask" "F.Paste")
			(net "GND")
		)
		(pad "D21" smd circle
			(at -7.500112 -12.065 90)
			(size 0.3048 0.3048)
			(layers "F.Cu" "F.Mask" "F.Paste")
			(net "CLK_100M_MEZZ4_DP")
		)
		(pad "D23" smd circle
			(at -6.500114 -12.065 90)
			(size 0.3048 0.3048)
			(layers "F.Cu" "F.Mask" "F.Paste")
			(net "CLK_100M_MEZZ3_DP")
		)
		(pad "D25" smd circle
			(at -5.500116 -12.065 90)
			(size 0.3048 0.3048)
			(layers "F.Cu" "F.Mask" "F.Paste")
			(net "GND")
		)
		(pad "D27" smd circle
			(at -4.500118 -12.065 90)
			(size 0.3048 0.3048)
			(layers "F.Cu" "F.Mask" "F.Paste")
			(net "GND")
		)
		(pad "D29" smd circle
			(at -3.50012 -12.065 90)
			(size 0.3048 0.3048)
			(layers "F.Cu" "F.Mask" "F.Paste")
			(net "CLK_100M_BMC_PE_DP")
		)
		(pad "D31" smd circle
			(at -2.500122 -12.065 90)
			(size 0.3048 0.3048)
			(layers "F.Cu" "F.Mask" "F.Paste")
			(net "CLK_100M_MEZZ1_DN")
		)
		(pad "D33" smd circle
			(at -1.500124 -12.065 90)
			(size 0.3048 0.3048)
			(layers "F.Cu" "F.Mask" "F.Paste")
			(net "CLK_100M_PCH_SLOTX24_S4_DN")
		)
		(pad "D35" smd circle
			(at -0.500126 -12.065 90)
			(size 0.3048 0.3048)
			(layers "F.Cu" "F.Mask" "F.Paste")
			(net "XTAL_PCH_48M_OUT")
		)
		(pad "D38" smd circle
			(at 0.500126 -12.065 90)
			(size 0.3048 0.3048)
			(layers "F.Cu" "F.Mask" "F.Paste")
			(net "TP_CLK_100M_NSSCC1_DP")
		)
		(pad "D40" smd circle
			(at 1.500124 -12.065 90)
			(size 0.3048 0.3048)
			(layers "F.Cu" "F.Mask" "F.Paste")
			(net "TP_CLK_100M_PLAT1_DP")
		)
		(pad "D42" smd circle
			(at 2.500122 -12.065 90)
			(size 0.3048 0.3048)
			(layers "F.Cu" "F.Mask" "F.Paste")
			(net "DMI_CPU0_PCH_TX_C_DN<0>")
		)
		(pad "D44" smd circle
			(at 3.50012 -12.065 90)
			(size 0.3048 0.3048)
			(layers "F.Cu" "F.Mask" "F.Paste")
			(net "DMI_CPU0_PCH_TX_C_DN<2>")
		)
		(pad "D47" smd circle
			(at 4.500118 -12.065 90)
			(size 0.3048 0.3048)
			(layers "F.Cu" "F.Mask" "F.Paste")
			(net "GND")
		)
		(pad "D49" smd circle
			(at 5.500116 -12.065 90)
			(size 0.3048 0.3048)
			(layers "F.Cu" "F.Mask" "F.Paste")
			(net "P3E_CPU0_PE1_PCH_TXN<1>")
		)
		(pad "D51" smd circle
			(at 6.500114 -12.065 90)
			(size 0.3048 0.3048)
			(layers "F.Cu" "F.Mask" "F.Paste")
			(net "P3E_CPU0_PE1_PCH_TXN<3>")
		)
		(pad "D53" smd circle
			(at 7.500112 -12.065 90)
			(size 0.3048 0.3048)
			(layers "F.Cu" "F.Mask" "F.Paste")
			(net "P3E_CPU0_PE1_PCH_TXN<5>")
		)
		(pad "D55" smd circle
			(at 8.50011 -12.065 90)
			(size 0.3048 0.3048)
			(layers "F.Cu" "F.Mask" "F.Paste")
			(net "P3E_CPU0_PE1_PCH_TXN<7>")
		)
		(pad "D58" smd circle
			(at 9.500108 -12.065 90)
			(size 0.3048 0.3048)
			(layers "F.Cu" "F.Mask" "F.Paste")
			(net "P3E_CPU0_PE1_PCH_C_TXP<9>")
		)
		(pad "D60" smd circle
			(at 10.500106 -12.065 90)
			(size 0.3048 0.3048)
			(layers "F.Cu" "F.Mask" "F.Paste")
			(net "P3E_CPU0_PE1_PCH_C_TXN<11>")
		)
		(pad "D62" smd circle
			(at 11.500104 -12.065 90)
			(size 0.3048 0.3048)
			(layers "F.Cu" "F.Mask" "F.Paste")
			(net "P3E_CPU0_PE1_PCH_C_TXP<13>")
		)
		(pad "D64" smd circle
			(at 12.500102 -12.065 90)
			(size 0.3048 0.3048)
			(layers "F.Cu" "F.Mask" "F.Paste")
			(net "P3E_CPU0_PE1_PCH_C_TXP<15>")
		)
		(pad "D66" smd circle
			(at 13.5001 -12.065 90)
			(size 0.3048 0.3048)
			(layers "F.Cu" "F.Mask" "F.Paste")
			(net "A_EXTCLKN")
		)
		(pad "E1" smd circle
			(at -16.310102 -11.689334 135)
			(size 0.4064 0.4064)
			(layers "F.Cu" "F.Mask" "F.Paste")
			(net "GND")
		)
		(pad "E3" smd circle
			(at -15.580106 -11.78433 90)
			(size 0.3556 0.3556)
			(layers "F.Cu" "F.Mask" "F.Paste")
			(net "GND")
		)
		(pad "E6" smd circle
			(at -14.100048 -11.700002 90)
			(size 0.3048 0.3048)
			(layers "F.Cu" "F.Mask" "F.Paste")
			(net "GND")
		)
		(pad "E9" smd circle
			(at -12.999974 -11.649964 90)
			(size 0.3048 0.3048)
			(layers "F.Cu" "F.Mask" "F.Paste")
			(net "GND")
		)
		(pad "E11" smd circle
			(at -11.999976 -11.649964 90)
			(size 0.3048 0.3048)
			(layers "F.Cu" "F.Mask" "F.Paste")
			(net "GND")
		)
		(pad "E13" smd circle
			(at -10.999978 -11.649964 90)
			(size 0.3048 0.3048)
			(layers "F.Cu" "F.Mask" "F.Paste")
			(net "GND")
		)
		(pad "E15" smd circle
			(at -9.99998 -11.649964 90)
			(size 0.3048 0.3048)
			(layers "F.Cu" "F.Mask" "F.Paste")
			(net "GND")
		)
		(pad "E18" smd circle
			(at -8.999982 -11.649964 90)
			(size 0.3048 0.3048)
			(layers "F.Cu" "F.Mask" "F.Paste")
			(net "TP_PCH_RSVD14")
		)
		(pad "E20" smd circle
			(at -7.999984 -11.649964 90)
			(size 0.3048 0.3048)
			(layers "F.Cu" "F.Mask" "F.Paste")
			(net "GND")
		)
		(pad "E22" smd circle
			(at -6.999986 -11.649964 90)
			(size 0.3048 0.3048)
			(layers "F.Cu" "F.Mask" "F.Paste")
			(net "GND")
		)
		(pad "E24" smd circle
			(at -5.999988 -11.649964 90)
			(size 0.3048 0.3048)
			(layers "F.Cu" "F.Mask" "F.Paste")
			(net "GND")
		)
		(pad "E26" smd circle
			(at -4.99999 -11.649964 90)
			(size 0.3048 0.3048)
			(layers "F.Cu" "F.Mask" "F.Paste")
			(net "GND")
		)
		(pad "E28" smd circle
			(at -3.999992 -11.649964 90)
			(size 0.3048 0.3048)
			(layers "F.Cu" "F.Mask" "F.Paste")
			(net "GND")
		)
		(pad "E30" smd circle
			(at -2.999994 -11.649964 90)
			(size 0.3048 0.3048)
			(layers "F.Cu" "F.Mask" "F.Paste")
			(net "GND")
		)
		(pad "E32" smd circle
			(at -1.999996 -11.649964 90)
			(size 0.3048 0.3048)
			(layers "F.Cu" "F.Mask" "F.Paste")
			(net "GND")
		)
		(pad "E34" smd circle
			(at -0.999998 -11.649964 90)
			(size 0.3048 0.3048)
			(layers "F.Cu" "F.Mask" "F.Paste")
			(net "GND")
		)
		(pad "E37" smd circle
			(at 0 -11.649964 90)
			(size 0.3048 0.3048)
			(layers "F.Cu" "F.Mask" "F.Paste")
			(net "GND")
		)
		(pad "E39" smd circle
			(at 0.999998 -11.649964 90)
			(size 0.3048 0.3048)
			(layers "F.Cu" "F.Mask" "F.Paste")
			(net "GND")
		)
		(pad "E41" smd circle
			(at 1.999996 -11.649964 90)
			(size 0.3048 0.3048)
			(layers "F.Cu" "F.Mask" "F.Paste")
			(net "GND")
		)
		(pad "E43" smd circle
			(at 2.999994 -11.649964 90)
			(size 0.3048 0.3048)
			(layers "F.Cu" "F.Mask" "F.Paste")
			(net "GND")
		)
		(pad "E45" smd circle
			(at 3.999992 -11.649964 90)
			(size 0.3048 0.3048)
			(layers "F.Cu" "F.Mask" "F.Paste")
			(net "GND")
		)
		(pad "E48" smd circle
			(at 4.99999 -11.649964 90)
			(size 0.3048 0.3048)
			(layers "F.Cu" "F.Mask" "F.Paste")
			(net "GND")
		)
		(pad "E50" smd circle
			(at 5.999988 -11.649964 90)
			(size 0.3048 0.3048)
			(layers "F.Cu" "F.Mask" "F.Paste")
			(net "GND")
		)
		(pad "E52" smd circle
			(at 6.999986 -11.649964 90)
			(size 0.3048 0.3048)
			(layers "F.Cu" "F.Mask" "F.Paste")
			(net "GND")
		)
		(pad "E54" smd circle
			(at 7.999984 -11.649964 90)
			(size 0.3048 0.3048)
			(layers "F.Cu" "F.Mask" "F.Paste")
			(net "GND")
		)
		(pad "E57" smd circle
			(at 8.999982 -11.649964 90)
			(size 0.3048 0.3048)
			(layers "F.Cu" "F.Mask" "F.Paste")
			(net "GND")
		)
		(pad "E59" smd circle
			(at 9.99998 -11.649964 90)
			(size 0.3048 0.3048)
			(layers "F.Cu" "F.Mask" "F.Paste")
			(net "GND")
		)
		(pad "E61" smd circle
			(at 10.999978 -11.649964 90)
			(size 0.3048 0.3048)
			(layers "F.Cu" "F.Mask" "F.Paste")
			(net "GND")
		)
		(pad "E63" smd circle
			(at 11.999976 -11.649964 90)
			(size 0.3048 0.3048)
			(layers "F.Cu" "F.Mask" "F.Paste")
			(net "GND")
		)
		(pad "E65" smd circle
			(at 12.999974 -11.649964 90)
			(size 0.3048 0.3048)
			(layers "F.Cu" "F.Mask" "F.Paste")
			(net "GND")
		)
		(pad "E67" smd circle
			(at 13.999972 -11.649964 90)
			(size 0.3048 0.3048)
			(layers "F.Cu" "F.Mask" "F.Paste")
			(net "A_EXTCLKP")
		)
		(pad "E70" smd circle
			(at 15.580106 -11.78433 90)
			(size 0.3556 0.3556)
			(layers "F.Cu" "F.Mask" "F.Paste")
			(net "GND")
		)
		(pad "E72" smd circle
			(at 16.310102 -11.689334 45)
			(size 0.4064 0.4064)
			(layers "F.Cu" "F.Mask" "F.Paste")
			(net "GND")
		)
		(pad "F3" smd circle
			(at -15.580106 -10.999978 90)
			(size 0.3556 0.3556)
			(layers "F.Cu" "F.Mask" "F.Paste")
			(net "GND")
		)
		(pad "F5" smd circle
			(at -14.85138 -11.386058 90)
			(size 0.3048 0.3048)
			(layers "F.Cu" "F.Mask" "F.Paste")
			(net "SPI_PCH_IO2")
		)
		(pad "F8" smd circle
			(at -13.599922 -11.284966 90)
			(size 0.3048 0.3048)
			(layers "F.Cu" "F.Mask" "F.Paste")
			(net "TP_PCH_RSVD7")
		)
		(pad "F66" smd circle
			(at 13.200126 -11.025124 315)
			(size 0.3048 0.3048)
			(layers "F.Cu" "F.Mask" "F.Paste")
			(net "TP_PCH_RSVD9")
		)
		(pad "F69" smd circle
			(at 14.85138 -11.386058 90)
			(size 0.3048 0.3048)
			(layers "F.Cu" "F.Mask" "F.Paste")
			(net "TP_PCH_RSVD8")
		)
		(pad "F70" smd circle
			(at 15.580106 -10.999978 90)
			(size 0.3556 0.3556)
			(layers "F.Cu" "F.Mask" "F.Paste")
			(net "GND")
		)
		(pad "G1" smd circle
			(at -16.310102 -10.876534 135)
			(size 0.4064 0.4064)
			(layers "F.Cu" "F.Mask" "F.Paste")
			(net "GND")
		)
		(pad "G6" smd circle
			(at -14.356334 -10.891012 90)
			(size 0.3048 0.3048)
			(layers "F.Cu" "F.Mask" "F.Paste")
			(net "GND")
		)
		(pad "G7" smd circle
			(at -13.73632 -10.64895)
			(size 0.381 0.381)
			(layers "F.Cu" "F.Mask" "F.Paste")
			(net "TP_SPI_PCH_CS1_R1_N")
		)
	)
)
